(kicad_pcb
	(version 20241229)
	(generator "pcbnew")
	(generator_version "9.0")
	(general
		(thickness 1.599998)
		(legacy_teardrops no)
	)
	(paper "A4")
	(title_block
		(title "Artix - Datacenter Secure Control Module (DC-SCM)")
		(date "2024-11-06")
		(rev "1.1.3")
		(comment 9 "footprints 484-489 of 544")
	)
	(layers
		(0 "F.Cu" signal)
		(4 "In1.Cu" signal)
		(6 "In2.Cu" signal)
		(8 "In3.Cu" signal)
		(10 "In4.Cu" signal)
		(12 "In5.Cu" signal)
		(14 "In6.Cu" signal)
		(2 "B.Cu" signal)
		(9 "F.Adhes" user "F.Adhesive")
		(11 "B.Adhes" user "B.Adhesive")
		(13 "F.Paste" user)
		(15 "B.Paste" user)
		(5 "F.SilkS" user "F.Silkscreen")
		(7 "B.SilkS" user "B.Silkscreen")
		(1 "F.Mask" user)
		(3 "B.Mask" user)
		(17 "Dwgs.User" user "User.Drawings")
		(19 "Cmts.User" user "User.Comments")
		(21 "Eco1.User" user "User.Eco1")
		(23 "Eco2.User" user "User.Eco2")
		(25 "Edge.Cuts" user)
		(27 "Margin" user)
		(31 "F.CrtYd" user "F.Courtyard")
		(29 "B.CrtYd" user "B.Courtyard")
		(35 "F.Fab" user)
		(33 "B.Fab" user)
	)
	(footprint "antmicro-footprints:R_0402_1005Metric"
		(layer "B.Cu")
		(at 105.575 145.175 90)
		(descr "Resistor SMD 0402")
		(tags "resistor SMD 0402")
		(property "Reference" "R173"
			(at 1.375 -8.675 90)
			(layer "B.SilkS")
			(effects
				(font
					(size 0.7 0.7)
					(thickness 0.15)
				)
				(justify right bottom mirror)
			)
		)
		(property "Value" "R_51R_0402"
			(at 0 -1.4 90)
			(layer "B.Fab")
			(effects
				(font
					(size 0.7 0.7)
					(thickness 0.15)
				)
				(justify right bottom mirror)
			)
		)
		(property "Datasheet" "https://www.bourns.com/docs/product-datasheets/cr.pdf"
			(at 0 0 90)
			(layer "F.Fab")
			(hide yes)
			(effects
				(font
					(size 1.27 1.27)
					(thickness 0.15)
				)
			)
		)
		(property "Description" "SMD Chip Resistor, 51 ohm, ± 1%, 63 mW, 0402 [1005 Metric], Thick Film, General Purpose"
			(at 0 0 90)
			(layer "F.Fab")
			(hide yes)
			(effects
				(font
					(size 1.27 1.27)
					(thickness 0.15)
				)
			)
		)
		(property "Author" "Antmicro"
			(at 250.75 39.6 0)
			(layer "B.Fab")
			(hide yes)
			(effects
				(font
					(size 1 1)
					(thickness 0.15)
				)
				(justify mirror)
			)
		)
		(property "License" "Apache-2.0"
			(at 250.75 39.6 0)
			(layer "B.Fab")
			(hide yes)
			(effects
				(font
					(size 1 1)
					(thickness 0.15)
				)
				(justify mirror)
			)
		)
		(property "MPN" "CR0402-FX-51R0GLF"
			(at 250.75 39.6 0)
			(layer "B.Fab")
			(hide yes)
			(effects
				(font
					(size 1 1)
					(thickness 0.15)
				)
				(justify mirror)
			)
		)
		(property "Manufacturer" "Bourns"
			(at 250.75 39.6 0)
			(layer "B.Fab")
			(hide yes)
			(effects
				(font
					(size 1 1)
					(thickness 0.15)
				)
				(justify mirror)
			)
		)
		(property "Tolerance" "1%"
			(at 250.75 39.6 0)
			(layer "B.Fab")
			(hide yes)
			(effects
				(font
					(size 1 1)
					(thickness 0.15)
				)
				(justify mirror)
			)
		)
		(property "Val" "51R"
			(at 250.75 39.6 0)
			(layer "B.Fab")
			(hide yes)
			(effects
				(font
					(size 1 1)
					(thickness 0.15)
				)
				(justify mirror)
			)
		)
		(sheetname "/DDR3/")
		(sheetfile "ddr3.kicad_sch")
		(attr smd exclude_from_pos_files exclude_from_bom dnp)
		(fp_rect
			(start -0.925 0.47)
			(end 0.925 -0.47)
			(stroke
				(width 0.05)
				(type default)
			)
			(fill no)
			(layer "B.CrtYd")
		)
		(fp_rect
			(start -0.5 0.25)
			(end 0.5 -0.25)
			(stroke
				(width 0.15)
				(type solid)
			)
			(fill no)
			(layer "B.Fab")
		)
		(pad "1" smd roundrect
			(at -0.48 0 90)
			(size 0.59 0.64)
			(layers "B.Cu" "B.Mask" "B.Paste")
			(roundrect_rratio 0.25)
			(net 151 "DDR3_A13")
			(pintype "passive")
		)
		(pad "2" smd roundrect
			(at 0.48 0 90)
			(size 0.59 0.64)
			(layers "B.Cu" "B.Mask" "B.Paste")
			(roundrect_rratio 0.25)
			(net 143 "/DDR3/DDR3_VTT")
			(pintype "passive")
		)
	)
	(footprint "antmicro-footprints:R_0402_1005Metric"
		(layer "B.Cu")
		(at 101.075 144.775 180)
		(descr "Resistor SMD 0402")
		(tags "resistor SMD 0402")
		(property "Reference" "R174"
			(at 7.975 2.775 0)
			(layer "B.SilkS")
			(effects
				(font
					(size 0.7 0.7)
					(thickness 0.15)
				)
				(justify left bottom mirror)
			)
		)
		(property "Value" "R_51R_0402"
			(at 0 -1.4 0)
			(layer "B.Fab")
			(effects
				(font
					(size 0.7 0.7)
					(thickness 0.15)
				)
				(justify left bottom mirror)
			)
		)
		(property "Datasheet" "https://www.bourns.com/docs/product-datasheets/cr.pdf"
			(at 0 0 180)
			(layer "F.Fab")
			(hide yes)
			(effects
				(font
					(size 1.27 1.27)
					(thickness 0.15)
				)
			)
		)
		(property "Description" "SMD Chip Resistor, 51 ohm, ± 1%, 63 mW, 0402 [1005 Metric], Thick Film, General Purpose"
			(at 0 0 180)
			(layer "F.Fab")
			(hide yes)
			(effects
				(font
					(size 1.27 1.27)
					(thickness 0.15)
				)
			)
		)
		(property "Author" "Antmicro"
			(at 202.15 289.55 0)
			(layer "B.Fab")
			(hide yes)
			(effects
				(font
					(size 1 1)
					(thickness 0.15)
				)
				(justify mirror)
			)
		)
		(property "License" "Apache-2.0"
			(at 202.15 289.55 0)
			(layer "B.Fab")
			(hide yes)
			(effects
				(font
					(size 1 1)
					(thickness 0.15)
				)
				(justify mirror)
			)
		)
		(property "MPN" "CR0402-FX-51R0GLF"
			(at 202.15 289.55 0)
			(layer "B.Fab")
			(hide yes)
			(effects
				(font
					(size 1 1)
					(thickness 0.15)
				)
				(justify mirror)
			)
		)
		(property "Manufacturer" "Bourns"
			(at 202.15 289.55 0)
			(layer "B.Fab")
			(hide yes)
			(effects
				(font
					(size 1 1)
					(thickness 0.15)
				)
				(justify mirror)
			)
		)
		(property "Tolerance" "1%"
			(at 202.15 289.55 0)
			(layer "B.Fab")
			(hide yes)
			(effects
				(font
					(size 1 1)
					(thickness 0.15)
				)
				(justify mirror)
			)
		)
		(property "Val" "51R"
			(at 202.15 289.55 0)
			(layer "B.Fab")
			(hide yes)
			(effects
				(font
					(size 1 1)
					(thickness 0.15)
				)
				(justify mirror)
			)
		)
		(sheetname "/DDR3/")
		(sheetfile "ddr3.kicad_sch")
		(attr smd exclude_from_pos_files exclude_from_bom dnp)
		(fp_rect
			(start -0.925 0.47)
			(end 0.925 -0.47)
			(stroke
				(width 0.05)
				(type default)
			)
			(fill no)
			(layer "B.CrtYd")
		)
		(fp_rect
			(start -0.5 0.25)
			(end 0.5 -0.25)
			(stroke
				(width 0.15)
				(type solid)
			)
			(fill no)
			(layer "B.Fab")
		)
		(pad "1" smd roundrect
			(at -0.48 0 180)
			(size 0.59 0.64)
			(layers "B.Cu" "B.Mask" "B.Paste")
			(roundrect_rratio 0.25)
			(net 156 "DDR3_A12")
			(pintype "passive")
		)
		(pad "2" smd roundrect
			(at 0.48 0 180)
			(size 0.59 0.64)
			(layers "B.Cu" "B.Mask" "B.Paste")
			(roundrect_rratio 0.25)
			(net 143 "/DDR3/DDR3_VTT")
			(pintype "passive")
		)
	)
	(footprint "antmicro-footprints:R_0402_1005Metric"
		(layer "B.Cu")
		(at 102.575 144.675 90)
		(descr "Resistor SMD 0402")
		(tags "resistor SMD 0402")
		(property "Reference" "R175"
			(at 1.375 -8.675 90)
			(layer "B.SilkS")
			(effects
				(font
					(size 0.7 0.7)
					(thickness 0.15)
				)
				(justify right bottom mirror)
			)
		)
		(property "Value" "R_51R_0402"
			(at 0 -1.4 90)
			(layer "B.Fab")
			(effects
				(font
					(size 0.7 0.7)
					(thickness 0.15)
				)
				(justify right bottom mirror)
			)
		)
		(property "Datasheet" "https://www.bourns.com/docs/product-datasheets/cr.pdf"
			(at 0 0 90)
			(layer "F.Fab")
			(hide yes)
			(effects
				(font
					(size 1.27 1.27)
					(thickness 0.15)
				)
			)
		)
		(property "Description" "SMD Chip Resistor, 51 ohm, ± 1%, 63 mW, 0402 [1005 Metric], Thick Film, General Purpose"
			(at 0 0 90)
			(layer "F.Fab")
			(hide yes)
			(effects
				(font
					(size 1.27 1.27)
					(thickness 0.15)
				)
			)
		)
		(property "Author" "Antmicro"
			(at 247.25 42.1 0)
			(layer "B.Fab")
			(hide yes)
			(effects
				(font
					(size 1 1)
					(thickness 0.15)
				)
				(justify mirror)
			)
		)
		(property "License" "Apache-2.0"
			(at 247.25 42.1 0)
			(layer "B.Fab")
			(hide yes)
			(effects
				(font
					(size 1 1)
					(thickness 0.15)
				)
				(justify mirror)
			)
		)
		(property "MPN" "CR0402-FX-51R0GLF"
			(at 247.25 42.1 0)
			(layer "B.Fab")
			(hide yes)
			(effects
				(font
					(size 1 1)
					(thickness 0.15)
				)
				(justify mirror)
			)
		)
		(property "Manufacturer" "Bourns"
			(at 247.25 42.1 0)
			(layer "B.Fab")
			(hide yes)
			(effects
				(font
					(size 1 1)
					(thickness 0.15)
				)
				(justify mirror)
			)
		)
		(property "Tolerance" "1%"
			(at 247.25 42.1 0)
			(layer "B.Fab")
			(hide yes)
			(effects
				(font
					(size 1 1)
					(thickness 0.15)
				)
				(justify mirror)
			)
		)
		(property "Val" "51R"
			(at 247.25 42.1 0)
			(layer "B.Fab")
			(hide yes)
			(effects
				(font
					(size 1 1)
					(thickness 0.15)
				)
				(justify mirror)
			)
		)
		(sheetname "/DDR3/")
		(sheetfile "ddr3.kicad_sch")
		(attr smd exclude_from_pos_files exclude_from_bom dnp)
		(fp_rect
			(start -0.925 0.47)
			(end 0.925 -0.47)
			(stroke
				(width 0.05)
				(type default)
			)
			(fill no)
			(layer "B.CrtYd")
		)
		(fp_rect
			(start -0.5 0.25)
			(end 0.5 -0.25)
			(stroke
				(width 0.15)
				(type solid)
			)
			(fill no)
			(layer "B.Fab")
		)
		(pad "1" smd roundrect
			(at -0.48 0 90)
			(size 0.59 0.64)
			(layers "B.Cu" "B.Mask" "B.Paste")
			(roundrect_rratio 0.25)
			(net 157 "DDR3_A1")
			(pintype "passive")
		)
		(pad "2" smd roundrect
			(at 0.48 0 90)
			(size 0.59 0.64)
			(layers "B.Cu" "B.Mask" "B.Paste")
			(roundrect_rratio 0.25)
			(net 143 "/DDR3/DDR3_VTT")
			(pintype "passive")
		)
	)
	(footprint "antmicro-footprints:R_0402_1005Metric"
		(layer "B.Cu")
		(at 103.575 144.675 90)
		(descr "Resistor SMD 0402")
		(tags "resistor SMD 0402")
		(property "Reference" "R176"
			(at 1.375 -8.675 90)
			(layer "B.SilkS")
			(effects
				(font
					(size 0.7 0.7)
					(thickness 0.15)
				)
				(justify right bottom mirror)
			)
		)
		(property "Value" "R_51R_0402"
			(at 0 -1.4 90)
			(layer "B.Fab")
			(effects
				(font
					(size 0.7 0.7)
					(thickness 0.15)
				)
				(justify right bottom mirror)
			)
		)
		(property "Datasheet" "https://www.bourns.com/docs/product-datasheets/cr.pdf"
			(at 0 0 90)
			(layer "F.Fab")
			(hide yes)
			(effects
				(font
					(size 1.27 1.27)
					(thickness 0.15)
				)
			)
		)
		(property "Description" "SMD Chip Resistor, 51 ohm, ± 1%, 63 mW, 0402 [1005 Metric], Thick Film, General Purpose"
			(at 0 0 90)
			(layer "F.Fab")
			(hide yes)
			(effects
				(font
					(size 1.27 1.27)
					(thickness 0.15)
				)
			)
		)
		(property "Author" "Antmicro"
			(at 248.25 41.1 0)
			(layer "B.Fab")
			(hide yes)
			(effects
				(font
					(size 1 1)
					(thickness 0.15)
				)
				(justify mirror)
			)
		)
		(property "License" "Apache-2.0"
			(at 248.25 41.1 0)
			(layer "B.Fab")
			(hide yes)
			(effects
				(font
					(size 1 1)
					(thickness 0.15)
				)
				(justify mirror)
			)
		)
		(property "MPN" "CR0402-FX-51R0GLF"
			(at 248.25 41.1 0)
			(layer "B.Fab")
			(hide yes)
			(effects
				(font
					(size 1 1)
					(thickness 0.15)
				)
				(justify mirror)
			)
		)
		(property "Manufacturer" "Bourns"
			(at 248.25 41.1 0)
			(layer "B.Fab")
			(hide yes)
			(effects
				(font
					(size 1 1)
					(thickness 0.15)
				)
				(justify mirror)
			)
		)
		(property "Tolerance" "1%"
			(at 248.25 41.1 0)
			(layer "B.Fab")
			(hide yes)
			(effects
				(font
					(size 1 1)
					(thickness 0.15)
				)
				(justify mirror)
			)
		)
		(property "Val" "51R"
			(at 248.25 41.1 0)
			(layer "B.Fab")
			(hide yes)
			(effects
				(font
					(size 1 1)
					(thickness 0.15)
				)
				(justify mirror)
			)
		)
		(sheetname "/DDR3/")
		(sheetfile "ddr3.kicad_sch")
		(attr smd exclude_from_pos_files exclude_from_bom dnp)
		(fp_rect
			(start -0.925 0.47)
			(end 0.925 -0.47)
			(stroke
				(width 0.05)
				(type default)
			)
			(fill no)
			(layer "B.CrtYd")
		)
		(fp_rect
			(start -0.5 0.25)
			(end 0.5 -0.25)
			(stroke
				(width 0.15)
				(type solid)
			)
			(fill no)
			(layer "B.Fab")
		)
		(pad "1" smd roundrect
			(at -0.48 0 90)
			(size 0.59 0.64)
			(layers "B.Cu" "B.Mask" "B.Paste")
			(roundrect_rratio 0.25)
			(net 150 "DDR3_A11")
			(pintype "passive")
		)
		(pad "2" smd roundrect
			(at 0.48 0 90)
			(size 0.59 0.64)
			(layers "B.Cu" "B.Mask" "B.Paste")
			(roundrect_rratio 0.25)
			(net 143 "/DDR3/DDR3_VTT")
			(pintype "passive")
		)
	)
	(footprint "antmicro-footprints:R_0402_1005Metric"
		(layer "B.Cu")
		(at 106.575 144.075 90)
		(descr "Resistor SMD 0402")
		(tags "resistor SMD 0402")
		(property "Reference" "R177"
			(at 0.775 -8.675 90)
			(layer "B.SilkS")
			(effects
				(font
					(size 0.7 0.7)
					(thickness 0.15)
				)
				(justify right bottom mirror)
			)
		)
		(property "Value" "R_51R_0402"
			(at 0 -1.4 90)
			(layer "B.Fab")
			(effects
				(font
					(size 0.7 0.7)
					(thickness 0.15)
				)
				(justify right bottom mirror)
			)
		)
		(property "Datasheet" "https://www.bourns.com/docs/product-datasheets/cr.pdf"
			(at 0 0 90)
			(layer "F.Fab")
			(hide yes)
			(effects
				(font
					(size 1.27 1.27)
					(thickness 0.15)
				)
			)
		)
		(property "Description" "SMD Chip Resistor, 51 ohm, ± 1%, 63 mW, 0402 [1005 Metric], Thick Film, General Purpose"
			(at 0 0 90)
			(layer "F.Fab")
			(hide yes)
			(effects
				(font
					(size 1.27 1.27)
					(thickness 0.15)
				)
			)
		)
		(property "Author" "Antmicro"
			(at 250.65 37.5 0)
			(layer "B.Fab")
			(hide yes)
			(effects
				(font
					(size 1 1)
					(thickness 0.15)
				)
				(justify mirror)
			)
		)
		(property "License" "Apache-2.0"
			(at 250.65 37.5 0)
			(layer "B.Fab")
			(hide yes)
			(effects
				(font
					(size 1 1)
					(thickness 0.15)
				)
				(justify mirror)
			)
		)
		(property "MPN" "CR0402-FX-51R0GLF"
			(at 250.65 37.5 0)
			(layer "B.Fab")
			(hide yes)
			(effects
				(font
					(size 1 1)
					(thickness 0.15)
				)
				(justify mirror)
			)
		)
		(property "Manufacturer" "Bourns"
			(at 250.65 37.5 0)
			(layer "B.Fab")
			(hide yes)
			(effects
				(font
					(size 1 1)
					(thickness 0.15)
				)
				(justify mirror)
			)
		)
		(property "Tolerance" "1%"
			(at 250.65 37.5 0)
			(layer "B.Fab")
			(hide yes)
			(effects
				(font
					(size 1 1)
					(thickness 0.15)
				)
				(justify mirror)
			)
		)
		(property "Val" "51R"
			(at 250.65 37.5 0)
			(layer "B.Fab")
			(hide yes)
			(effects
				(font
					(size 1 1)
					(thickness 0.15)
				)
				(justify mirror)
			)
		)
		(sheetname "/DDR3/")
		(sheetfile "ddr3.kicad_sch")
		(attr smd exclude_from_pos_files exclude_from_bom dnp)
		(fp_rect
			(start -0.925 0.47)
			(end 0.925 -0.47)
			(stroke
				(width 0.05)
				(type default)
			)
			(fill no)
			(layer "B.CrtYd")
		)
		(fp_rect
			(start -0.5 0.25)
			(end 0.5 -0.25)
			(stroke
				(width 0.15)
				(type solid)
			)
			(fill no)
			(layer "B.Fab")
		)
		(pad "1" smd roundrect
			(at -0.48 0 90)
			(size 0.59 0.64)
			(layers "B.Cu" "B.Mask" "B.Paste")
			(roundrect_rratio 0.25)
			(net 144 "DDR3_A14")
			(pintype "passive")
		)
		(pad "2" smd roundrect
			(at 0.48 0 90)
			(size 0.59 0.64)
			(layers "B.Cu" "B.Mask" "B.Paste")
			(roundrect_rratio 0.25)
			(net 143 "/DDR3/DDR3_VTT")
			(pintype "passive")
		)
	)
	(footprint "antmicro-footprints:R_0402_1005Metric"
		(layer "B.Cu")
		(at 102.175 141.875 90)
		(descr "Resistor SMD 0402")
		(tags "resistor SMD 0402")
		(property "Reference" "R178"
			(at 0.775 0.425 90)
			(layer "B.SilkS")
			(effects
				(font
					(size 0.7 0.7)
					(thickness 0.15)
				)
				(justify right bottom mirror)
			)
		)
		(property "Value" "R_51R_0402"
			(at 0 -1.4 90)
			(layer "B.Fab")
			(effects
				(font
					(size 0.7 0.7)
					(thickness 0.15)
				)
				(justify right bottom mirror)
			)
		)
		(property "Datasheet" "https://www.bourns.com/docs/product-datasheets/cr.pdf"
			(at 0 0 90)
			(layer "F.Fab")
			(hide yes)
			(effects
				(font
					(size 1.27 1.27)
					(thickness 0.15)
				)
			)
		)
		(property "Description" "SMD Chip Resistor, 51 ohm, ± 1%, 63 mW, 0402 [1005 Metric], Thick Film, General Purpose"
			(at 0 0 90)
			(layer "F.Fab")
			(hide yes)
			(effects
				(font
					(size 1.27 1.27)
					(thickness 0.15)
				)
			)
		)
		(property "Author" "Antmicro"
			(at 244.05 39.7 0)
			(layer "B.Fab")
			(hide yes)
			(effects
				(font
					(size 1 1)
					(thickness 0.15)
				)
				(justify mirror)
			)
		)
		(property "License" "Apache-2.0"
			(at 244.05 39.7 0)
			(layer "B.Fab")
			(hide yes)
			(effects
				(font
					(size 1 1)
					(thickness 0.15)
				)
				(justify mirror)
			)
		)
		(property "MPN" "CR0402-FX-51R0GLF"
			(at 244.05 39.7 0)
			(layer "B.Fab")
			(hide yes)
			(effects
				(font
					(size 1 1)
					(thickness 0.15)
				)
				(justify mirror)
			)
		)
		(property "Manufacturer" "Bourns"
			(at 244.05 39.7 0)
			(layer "B.Fab")
			(hide yes)
			(effects
				(font
					(size 1 1)
					(thickness 0.15)
				)
				(justify mirror)
			)
		)
		(property "Tolerance" "1%"
			(at 244.05 39.7 0)
			(layer "B.Fab")
			(hide yes)
			(effects
				(font
					(size 1 1)
					(thickness 0.15)
				)
				(justify mirror)
			)
		)
		(property "Val" "51R"
			(at 244.05 39.7 0)
			(layer "B.Fab")
			(hide yes)
			(effects
				(font
					(size 1 1)
					(thickness 0.15)
				)
				(justify mirror)
			)
		)
		(sheetname "/DDR3/")
		(sheetfile "ddr3.kicad_sch")
		(attr smd exclude_from_pos_files exclude_from_bom dnp)
		(fp_rect
			(start -0.925 0.47)
			(end 0.925 -0.47)
			(stroke
				(width 0.05)
				(type default)
			)
			(fill no)
			(layer "B.CrtYd")
		)
		(fp_rect
			(start -0.5 0.25)
			(end 0.5 -0.25)
			(stroke
				(width 0.15)
				(type solid)
			)
			(fill no)
			(layer "B.Fab")
		)
		(pad "1" smd roundrect
			(at -0.48 0 90)
			(size 0.59 0.64)
			(layers "B.Cu" "B.Mask" "B.Paste")
			(roundrect_rratio 0.25)
			(net 159 "DDR3_A4")
			(pintype "passive")
		)
		(pad "2" smd roundrect
			(at 0.48 0 90)
			(size 0.59 0.64)
			(layers "B.Cu" "B.Mask" "B.Paste")
			(roundrect_rratio 0.25)
			(net 143 "/DDR3/DDR3_VTT")
			(pintype "passive")
		)
	)
)
